(kicad_pcb
	(version 20260206)
	(generator "pcbnew")
	(generator_version "10.0")
	(general
		(thickness 1.6)
		(legacy_teardrops no)
	)
	(paper "A4")
	(title_block
		(title "v1-tray-backplane — T6M_tray_BP_c_1023_1120.brd")
		(comment 1 "Open CloudServer (Microsoft) / footprints 57-62 of 170")
	)
	(layers
		(0 "F.Cu" signal "TOP")
		(4 "In1.Cu" signal "GND")
		(6 "In2.Cu" signal "IN1")
		(8 "In3.Cu" signal "VCC")
		(10 "In4.Cu" signal "VCC1")
		(12 "In5.Cu" signal "IN2")
		(14 "In6.Cu" signal "GND1")
		(2 "B.Cu" signal "BOTTOM")
		(9 "F.Adhes" user "F.Adhesive")
		(11 "B.Adhes" user "B.Adhesive")
		(13 "F.Paste" user "Package Geometry/Pastemask Top")
		(15 "B.Paste" user "Package Geometry/Pastemask Bottom")
		(5 "F.SilkS" user "Ref Des/Silkscreen Top")
		(7 "B.SilkS" user "Ref Des/Silkscreen Bottom")
		(1 "F.Mask" user "Board Geometry/Soldermask Top")
		(3 "B.Mask" user "Board Geometry/Soldermask Bottom")
		(17 "Dwgs.User" user "User.Drawings")
		(19 "Cmts.User" user "User.Comments")
		(21 "Eco1.User" user "User.Eco1")
		(23 "Eco2.User" user "User.Eco2")
		(25 "Edge.Cuts" user "Board Geometry/Outline")
		(27 "Margin" user)
		(31 "F.CrtYd" user "Package Geometry/Place Bound Top")
		(29 "B.CrtYd" user "Package Geometry/Place Bound Bottom")
		(35 "F.Fab" user "Ref Des/Assembly Top")
		(33 "B.Fab" user "Ref Des/Assembly Bottom")
	)
	(footprint ""
		(layer "F.Cu")
		(at 377.063 -32.094932 180)
		(property "Reference" "R81"
			(at -34.29 -19.258534 0)
			(unlocked yes)
			(layer "F.SilkS")
			(effects
				(font
					(size 0.7874 0.5842)
					(thickness 0.1524)
				)
				(justify left)
			)
		)
		(property "Value" ""
			(at 0 0 180)
			(layer "F.Fab")
			(effects
				(font
					(size 1.27 1.27)
				)
			)
		)
		(duplicate_pad_numbers_are_jumpers no)
		(fp_line
			(start 1.905 0.8636)
			(end -1.905 0.8636)
			(stroke
				(width 0.1524)
				(type default)
			)
			(layer "F.SilkS")
		)
		(fp_line
			(start 1.905 -0.8636)
			(end 1.905 0.8636)
			(stroke
				(width 0.1524)
				(type default)
			)
			(layer "F.SilkS")
		)
		(fp_line
			(start -1.905 0.8636)
			(end -1.905 -0.8636)
			(stroke
				(width 0.1524)
				(type default)
			)
			(layer "F.SilkS")
		)
		(fp_line
			(start -1.905 -0.8636)
			(end 1.905 -0.8636)
			(stroke
				(width 0.1524)
				(type default)
			)
			(layer "F.SilkS")
		)
		(fp_poly
			(pts
				(xy 1.524 0.6858) (xy 1.524 -0.6858) (xy 1.524 -0.7366) (xy -1.524 -0.7366) (xy -1.524 -0.6858)
				(xy -1.524 0.6858) (xy -1.524 0.7366) (xy 1.524 0.7366)
			)
			(stroke
				(width 0)
				(type default)
			)
			(fill no)
			(layer "F.CrtYd")
		)
		(pad "1" smd rect
			(at 0.94996 0 180)
			(size 1.1176 1.3716)
			(layers "F.Cu" "F.Mask" "F.Paste")
			(net "P3V3_BLAD2")
		)
		(pad "2" smd rect
			(at -0.94996 0 180)
			(size 1.1176 1.3716)
			(layers "F.Cu" "F.Mask" "F.Paste")
			(net "P3V3_10G_3_VCCR")
		)
	)
	(footprint ""
		(layer "F.Cu")
		(at 351.208848 -26.533094 180)
		(property "Reference" "R21"
			(at 58.940192 4.17576 0)
			(unlocked yes)
			(layer "F.SilkS")
			(effects
				(font
					(size 0.7874 0.5842)
					(thickness 0.1524)
				)
				(justify left)
			)
		)
		(property "Value" ""
			(at 0 0 180)
			(layer "F.Fab")
			(effects
				(font
					(size 1.27 1.27)
				)
			)
		)
		(duplicate_pad_numbers_are_jumpers no)
		(fp_line
			(start 0.7874 0.4064)
			(end -0.7874 0.4064)
			(stroke
				(width 0.1524)
				(type default)
			)
			(layer "F.SilkS")
		)
		(fp_line
			(start 0.7874 -0.4064)
			(end 0.7874 0.4064)
			(stroke
				(width 0.1524)
				(type default)
			)
			(layer "F.SilkS")
		)
		(fp_line
			(start -0.7874 0.4064)
			(end -0.7874 -0.4064)
			(stroke
				(width 0.1524)
				(type default)
			)
			(layer "F.SilkS")
		)
		(fp_line
			(start -0.7874 -0.4064)
			(end 0.7874 -0.4064)
			(stroke
				(width 0.1524)
				(type default)
			)
			(layer "F.SilkS")
		)
		(fp_poly
			(pts
				(xy -0.508 0.2794) (xy -0.508 0.2286) (xy -0.635 0.2286) (xy -0.635 -0.254) (xy -0.5334 -0.254)
				(xy -0.5334 -0.2794) (xy 0.5334 -0.2794) (xy 0.5334 -0.254) (xy 0.635 -0.254) (xy 0.635 0.254) (xy 0.5334 0.254)
				(xy 0.5334 0.2794)
			)
			(stroke
				(width 0)
				(type default)
			)
			(fill no)
			(layer "F.CrtYd")
		)
		(pad "1" smd rect
			(at 0.40005 0 180)
			(size 0.4572 0.508)
			(layers "F.Cu" "F.Mask" "F.Paste")
			(net "P3V3_BLAD2")
		)
		(pad "2" smd rect
			(at -0.40005 0 180)
			(size 0.4572 0.508)
			(layers "F.Cu" "F.Mask" "F.Paste")
			(net "ENET10G_3_SDA")
		)
	)
	(footprint ""
		(layer "F.Cu")
		(at 346.521532 -21.657818 90)
		(property "Reference" "R64"
			(at 3.3528 -57.038748 90)
			(unlocked yes)
			(layer "F.SilkS")
			(effects
				(font
					(size 0.7874 0.5842)
					(thickness 0.1524)
				)
				(justify left)
			)
		)
		(property "Value" ""
			(at 0 0 90)
			(layer "F.Fab")
			(effects
				(font
					(size 1.27 1.27)
				)
			)
		)
		(duplicate_pad_numbers_are_jumpers no)
		(fp_line
			(start 0.7874 -0.4064)
			(end 0.7874 0.4064)
			(stroke
				(width 0.1524)
				(type default)
			)
			(layer "F.SilkS")
		)
		(fp_line
			(start -0.7874 -0.4064)
			(end 0.7874 -0.4064)
			(stroke
				(width 0.1524)
				(type default)
			)
			(layer "F.SilkS")
		)
		(fp_line
			(start 0.7874 0.4064)
			(end -0.7874 0.4064)
			(stroke
				(width 0.1524)
				(type default)
			)
			(layer "F.SilkS")
		)
		(fp_line
			(start -0.7874 0.4064)
			(end -0.7874 -0.4064)
			(stroke
				(width 0.1524)
				(type default)
			)
			(layer "F.SilkS")
		)
		(fp_poly
			(pts
				(xy -0.508 0.2794) (xy -0.508 0.2286) (xy -0.635 0.2286) (xy -0.635 -0.254) (xy -0.5334 -0.254)
				(xy -0.5334 -0.2794) (xy 0.5334 -0.2794) (xy 0.5334 -0.254) (xy 0.635 -0.254) (xy 0.635 0.254) (xy 0.5334 0.254)
				(xy 0.5334 0.2794)
			)
			(stroke
				(width 0)
				(type default)
			)
			(fill no)
			(layer "F.CrtYd")
		)
		(pad "1" smd rect
			(at 0.40005 0 90)
			(size 0.4572 0.508)
			(layers "F.Cu" "F.Mask" "F.Paste")
			(net "GND")
		)
		(pad "2" smd rect
			(at -0.40005 0 90)
			(size 0.4572 0.508)
			(layers "F.Cu" "F.Mask" "F.Paste")
			(net "SKU_PIN_BLAD2_1")
		)
	)
	(footprint ""
		(layer "F.Cu")
		(at 146.3294 -3.048 90)
		(property "Reference" "C17"
			(at -2.2606 -8.143748 90)
			(unlocked yes)
			(layer "F.SilkS")
			(effects
				(font
					(size 0.7874 0.5842)
					(thickness 0.1524)
				)
				(justify left)
			)
		)
		(property "Value" ""
			(at 0 0 90)
			(layer "F.Fab")
			(effects
				(font
					(size 1.27 1.27)
				)
			)
		)
		(duplicate_pad_numbers_are_jumpers no)
		(fp_line
			(start 0.7874 -0.4064)
			(end 0.7874 0.4064)
			(stroke
				(width 0.1524)
				(type default)
			)
			(layer "F.SilkS")
		)
		(fp_line
			(start -0.7874 -0.4064)
			(end 0.7874 -0.4064)
			(stroke
				(width 0.1524)
				(type default)
			)
			(layer "F.SilkS")
		)
		(fp_line
			(start 0 0.381)
			(end 0 -0.381)
			(stroke
				(width 0.1524)
				(type default)
			)
			(layer "F.SilkS")
		)
		(fp_line
			(start 0.7874 0.4064)
			(end -0.7874 0.4064)
			(stroke
				(width 0.1524)
				(type default)
			)
			(layer "F.SilkS")
		)
		(fp_line
			(start -0.7874 0.4064)
			(end -0.7874 -0.4064)
			(stroke
				(width 0.1524)
				(type default)
			)
			(layer "F.SilkS")
		)
		(fp_poly
			(pts
				(xy -0.5334 0.254) (xy -0.635 0.254) (xy -0.635 0.2286) (xy -0.635 -0.254) (xy -0.5334 -0.254) (xy -0.5334 -0.2794)
				(xy 0.5334 -0.2794) (xy 0.5334 -0.254) (xy 0.635 -0.254) (xy 0.635 0.254) (xy 0.5334 0.254) (xy 0.5334 0.2794)
				(xy -0.508 0.2794) (xy -0.5334 0.2794)
			)
			(stroke
				(width 0)
				(type default)
			)
			(fill no)
			(layer "F.CrtYd")
		)
		(pad "1" smd rect
			(at 0.40005 0 90)
			(size 0.4572 0.508)
			(layers "F.Cu" "F.Mask" "F.Paste")
			(net "P3V3_10G_1_VCCT")
		)
		(pad "2" smd rect
			(at -0.40005 0 90)
			(size 0.4572 0.508)
			(layers "F.Cu" "F.Mask" "F.Paste")
			(net "GND")
		)
	)
	(footprint ""
		(layer "F.Cu")
		(at 312.1406 -34.173668)
		(property "Reference" "R82"
			(at -1.3716 -8.05053 0)
			(unlocked yes)
			(layer "F.SilkS")
			(effects
				(font
					(size 0.7874 0.5842)
					(thickness 0.1524)
				)
				(justify left)
			)
		)
		(property "Value" ""
			(at 0 0 0)
			(layer "F.Fab")
			(effects
				(font
					(size 1.27 1.27)
				)
			)
		)
		(duplicate_pad_numbers_are_jumpers no)
		(fp_line
			(start -1.905 -0.8636)
			(end 1.905 -0.8636)
			(stroke
				(width 0.1524)
				(type default)
			)
			(layer "F.SilkS")
		)
		(fp_line
			(start -1.905 0.8636)
			(end -1.905 -0.8636)
			(stroke
				(width 0.1524)
				(type default)
			)
			(layer "F.SilkS")
		)
		(fp_line
			(start 1.905 -0.8636)
			(end 1.905 0.8636)
			(stroke
				(width 0.1524)
				(type default)
			)
			(layer "F.SilkS")
		)
		(fp_line
			(start 1.905 0.8636)
			(end -1.905 0.8636)
			(stroke
				(width 0.1524)
				(type default)
			)
			(layer "F.SilkS")
		)
		(fp_poly
			(pts
				(xy 1.524 0.6858) (xy 1.524 -0.6858) (xy 1.524 -0.7366) (xy -1.524 -0.7366) (xy -1.524 -0.6858)
				(xy -1.524 0.6858) (xy -1.524 0.7366) (xy 1.524 0.7366)
			)
			(stroke
				(width 0)
				(type default)
			)
			(fill no)
			(layer "F.CrtYd")
		)
		(pad "1" smd rect
			(at 0.94996 0)
			(size 1.1176 1.3716)
			(layers "F.Cu" "F.Mask" "F.Paste")
			(net "P3V3_BLAD2")
		)
		(pad "2" smd rect
			(at -0.94996 0)
			(size 1.1176 1.3716)
			(layers "F.Cu" "F.Mask" "F.Paste")
			(net "P3V3_10G_4_VCCT")
		)
	)
	(footprint ""
		(layer "F.Cu")
		(at 338.127848 -21.803106)
		(property "Reference" "R22"
			(at -58.3438 -4.587748 0)
			(unlocked yes)
			(layer "F.SilkS")
			(effects
				(font
					(size 0.7874 0.5842)
					(thickness 0.1524)
				)
				(justify left)
			)
		)
		(property "Value" ""
			(at 0 0 0)
			(layer "F.Fab")
			(effects
				(font
					(size 1.27 1.27)
				)
			)
		)
		(duplicate_pad_numbers_are_jumpers no)
		(fp_line
			(start -0.7874 -0.4064)
			(end 0.7874 -0.4064)
			(stroke
				(width 0.1524)
				(type default)
			)
			(layer "F.SilkS")
		)
		(fp_line
			(start -0.7874 0.4064)
			(end -0.7874 -0.4064)
			(stroke
				(width 0.1524)
				(type default)
			)
			(layer "F.SilkS")
		)
		(fp_line
			(start 0.7874 -0.4064)
			(end 0.7874 0.4064)
			(stroke
				(width 0.1524)
				(type default)
			)
			(layer "F.SilkS")
		)
		(fp_line
			(start 0.7874 0.4064)
			(end -0.7874 0.4064)
			(stroke
				(width 0.1524)
				(type default)
			)
			(layer "F.SilkS")
		)
		(fp_poly
			(pts
				(xy -0.508 0.2794) (xy -0.508 0.2286) (xy -0.635 0.2286) (xy -0.635 -0.254) (xy -0.5334 -0.254)
				(xy -0.5334 -0.2794) (xy 0.5334 -0.2794) (xy 0.5334 -0.254) (xy 0.635 -0.254) (xy 0.635 0.254) (xy 0.5334 0.254)
				(xy 0.5334 0.2794)
			)
			(stroke
				(width 0)
				(type default)
			)
			(fill no)
			(layer "F.CrtYd")
		)
		(pad "1" smd rect
			(at 0.40005 0)
			(size 0.4572 0.508)
			(layers "F.Cu" "F.Mask" "F.Paste")
			(net "P3V3_BLAD2")
		)
		(pad "2" smd rect
			(at -0.40005 0)
			(size 0.4572 0.508)
			(layers "F.Cu" "F.Mask" "F.Paste")
			(net "ENET10G_4_SDA")
		)
	)
)
